(kicad_pcb
	(version 20260206)
	(generator "pcbnew")
	(generator_version "10.0")
	(general
		(thickness 1.6)
		(legacy_teardrops no)
	)
	(paper "A4")
	(title_block
		(title "peb — Lightning_PEB_BRD.brd")
		(comment 1 "Lightning (Wiwynn / Facebook NVMe JBOF) / footprints 913-919 of 2563")
	)
	(layers
		(0 "F.Cu" signal "TOP")
		(4 "In1.Cu" signal "L2GND")
		(6 "In2.Cu" signal "L3")
		(8 "In3.Cu" signal "L4VCC")
		(10 "In4.Cu" signal "L5VCC")
		(12 "In5.Cu" signal "L6")
		(14 "In6.Cu" signal "L7GND")
		(2 "B.Cu" signal "BOTTOM")
		(9 "F.Adhes" user "F.Adhesive")
		(11 "B.Adhes" user "B.Adhesive")
		(13 "F.Paste" user "Package Geometry/Pastemask Top")
		(15 "B.Paste" user "Package Geometry/Pastemask Bottom")
		(5 "F.SilkS" user "Ref Des/Silkscreen Top")
		(7 "B.SilkS" user "Ref Des/Silkscreen Bottom")
		(1 "F.Mask" user "Board Geometry/Soldermask Top")
		(3 "B.Mask" user "Board Geometry/Soldermask Bottom")
		(17 "Dwgs.User" user "User.Drawings")
		(19 "Cmts.User" user "User.Comments")
		(21 "Eco1.User" user "User.Eco1")
		(23 "Eco2.User" user "User.Eco2")
		(25 "Edge.Cuts" user "Board Geometry/Outline")
		(27 "Margin" user)
		(31 "F.CrtYd" user "Package Geometry/Place Bound Top")
		(29 "B.CrtYd" user "Package Geometry/Place Bound Bottom")
		(35 "F.Fab" user "Ref Des/Assembly Top")
		(33 "B.Fab" user "Ref Des/Assembly Bottom")
	)
	(footprint ""
		(layer "F.Cu")
		(at 22.72919 -123.445016 90)
		(property "Reference" "C368"
			(at 0 0 90)
			(layer "F.SilkS")
			(hide yes)
			(effects
				(font
					(size 1.27 1.27)
				)
			)
		)
		(property "Value" "SCD22U10V2KX-1GP"
			(at 1.1811 -2.7051 90)
			(unlocked yes)
			(layer "F.Fab")
			(hide yes)
			(effects
				(font
					(size 1.016 1.016)
					(thickness 0.1524)
				)
			)
		)
		(property "Device Type" "C402H22"
			(at 1.1811 -4.2291 90)
			(unlocked yes)
			(layer "F.Fab")
			(hide yes)
			(effects
				(font
					(size 1.016 1.016)
					(thickness 0.1524)
				)
			)
		)
		(duplicate_pad_numbers_are_jumpers no)
		(fp_rect
			(start -0.4318 0.9525)
			(end 0.4318 -0.9525)
			(stroke
				(width 0)
				(type default)
			)
			(fill no)
			(layer "F.CrtYd")
		)
		(fp_rect
			(start -0.4318 0.9525)
			(end 0.4318 -0.9525)
			(stroke
				(width 0)
				(type default)
			)
			(fill no)
			(layer "F.Fab")
		)
		(pad "1" smd custom
			(at 0 -0.4445 90)
			(size 0.1524 0.1524)
			(layers "F.Cu" "F.Mask" "F.Paste")
			(net "PCIE_TX_CAP_N76")
			(options
				(clearance outline)
				(anchor circle)
			)
			(primitives
				(gr_poly
					(pts
						(arc
							(start 0.3048 -0.2032)
							(mid 0.275042 -0.275042)
							(end 0.2032 -0.3048)
						)
						(arc
							(start -0.2032 -0.3048)
							(mid -0.275042 -0.275042)
							(end -0.3048 -0.2032)
						)
						(arc
							(start -0.3048 0.2032)
							(mid -0.275042 0.275042)
							(end -0.2032 0.3048)
						)
						(arc
							(start 0.2032 0.3048)
							(mid 0.275042 0.275042)
							(end 0.3048 0.2032)
						)
					)
					(width 0)
					(fill yes)
				)
			)
		)
		(pad "2" smd custom
			(at 0 0.4445 90)
			(size 0.1524 0.1524)
			(layers "F.Cu" "F.Mask" "F.Paste")
			(net "PCIE_TX_N76")
			(options
				(clearance outline)
				(anchor circle)
			)
			(primitives
				(gr_poly
					(pts
						(arc
							(start 0.3048 -0.2032)
							(mid 0.275042 -0.275042)
							(end 0.2032 -0.3048)
						)
						(arc
							(start -0.2032 -0.3048)
							(mid -0.275042 -0.275042)
							(end -0.3048 -0.2032)
						)
						(arc
							(start -0.3048 0.2032)
							(mid -0.275042 0.275042)
							(end -0.2032 0.3048)
						)
						(arc
							(start 0.2032 0.3048)
							(mid 0.275042 0.275042)
							(end 0.3048 0.2032)
						)
					)
					(width 0)
					(fill yes)
				)
			)
		)
	)
	(footprint ""
		(layer "F.Cu")
		(at 154.813 -92.992702)
		(property "Reference" "C413"
			(at 0 0 0)
			(layer "F.SilkS")
			(hide yes)
			(effects
				(font
					(size 1.27 1.27)
				)
			)
		)
		(property "Value" "SC12P50V2JN-3GP"
			(at 1.1811 -2.7051 0)
			(unlocked yes)
			(layer "F.Fab")
			(hide yes)
			(effects
				(font
					(size 1.016 1.016)
					(thickness 0.1524)
				)
			)
		)
		(property "Device Type" "C402H24"
			(at 1.1811 -4.2291 0)
			(unlocked yes)
			(layer "F.Fab")
			(hide yes)
			(effects
				(font
					(size 1.016 1.016)
					(thickness 0.1524)
				)
			)
		)
		(duplicate_pad_numbers_are_jumpers no)
		(fp_rect
			(start -0.4318 0.9525)
			(end 0.4318 -0.9525)
			(stroke
				(width 0)
				(type default)
			)
			(fill no)
			(layer "F.CrtYd")
		)
		(fp_rect
			(start -0.4318 0.9525)
			(end 0.4318 -0.9525)
			(stroke
				(width 0)
				(type default)
			)
			(fill no)
			(layer "F.Fab")
		)
		(pad "1" smd custom
			(at 0 -0.4445)
			(size 0.1524 0.1524)
			(layers "F.Cu" "F.Mask" "F.Paste")
			(net "XTAL_X1")
			(options
				(clearance outline)
				(anchor circle)
			)
			(primitives
				(gr_poly
					(pts
						(arc
							(start 0.3048 -0.2032)
							(mid 0.275042 -0.275042)
							(end 0.2032 -0.3048)
						)
						(arc
							(start -0.2032 -0.3048)
							(mid -0.275042 -0.275042)
							(end -0.3048 -0.2032)
						)
						(arc
							(start -0.3048 0.2032)
							(mid -0.275042 0.275042)
							(end -0.2032 0.3048)
						)
						(arc
							(start 0.2032 0.3048)
							(mid 0.275042 0.275042)
							(end 0.3048 0.2032)
						)
					)
					(width 0)
					(fill yes)
				)
			)
		)
		(pad "2" smd custom
			(at 0 0.4445)
			(size 0.1524 0.1524)
			(layers "F.Cu" "F.Mask" "F.Paste")
			(net "GND")
			(options
				(clearance outline)
				(anchor circle)
			)
			(primitives
				(gr_poly
					(pts
						(arc
							(start 0.3048 -0.2032)
							(mid 0.275042 -0.275042)
							(end 0.2032 -0.3048)
						)
						(arc
							(start -0.2032 -0.3048)
							(mid -0.275042 -0.275042)
							(end -0.3048 -0.2032)
						)
						(arc
							(start -0.3048 0.2032)
							(mid -0.275042 0.275042)
							(end -0.2032 0.3048)
						)
						(arc
							(start 0.2032 0.3048)
							(mid 0.275042 0.275042)
							(end 0.3048 0.2032)
						)
					)
					(width 0)
					(fill yes)
				)
			)
		)
	)
	(footprint ""
		(layer "F.Cu")
		(at 5.5372 -46.3804 180)
		(property "Reference" "C333"
			(at 0 0 180)
			(layer "F.SilkS")
			(hide yes)
			(effects
				(font
					(size 1.27 1.27)
				)
			)
		)
		(property "Value" "SCD1U16V2KX-3GP"
			(at 1.1811 -2.7051 180)
			(unlocked yes)
			(layer "F.Fab")
			(hide yes)
			(effects
				(font
					(size 1.016 1.016)
					(thickness 0.1524)
				)
			)
		)
		(property "Device Type" "C402H22"
			(at 1.1811 -4.2291 180)
			(unlocked yes)
			(layer "F.Fab")
			(hide yes)
			(effects
				(font
					(size 1.016 1.016)
					(thickness 0.1524)
				)
			)
		)
		(duplicate_pad_numbers_are_jumpers no)
		(fp_rect
			(start -0.4318 0.9525)
			(end 0.4318 -0.9525)
			(stroke
				(width 0)
				(type default)
			)
			(fill no)
			(layer "F.CrtYd")
		)
		(fp_rect
			(start -0.4318 0.9525)
			(end 0.4318 -0.9525)
			(stroke
				(width 0)
				(type default)
			)
			(fill no)
			(layer "F.Fab")
		)
		(pad "1" smd custom
			(at 0 -0.4445 180)
			(size 0.1524 0.1524)
			(layers "F.Cu" "F.Mask" "F.Paste")
			(net "NIC0_CT_POWER")
			(options
				(clearance outline)
				(anchor circle)
			)
			(primitives
				(gr_poly
					(pts
						(arc
							(start 0.3048 -0.2032)
							(mid 0.275042 -0.275042)
							(end 0.2032 -0.3048)
						)
						(arc
							(start -0.2032 -0.3048)
							(mid -0.275042 -0.275042)
							(end -0.3048 -0.2032)
						)
						(arc
							(start -0.3048 0.2032)
							(mid -0.275042 0.275042)
							(end -0.2032 0.3048)
						)
						(arc
							(start 0.2032 0.3048)
							(mid 0.275042 0.275042)
							(end 0.3048 0.2032)
						)
					)
					(width 0)
					(fill yes)
				)
			)
		)
		(pad "2" smd custom
			(at 0 0.4445 180)
			(size 0.1524 0.1524)
			(layers "F.Cu" "F.Mask" "F.Paste")
			(net "GND")
			(options
				(clearance outline)
				(anchor circle)
			)
			(primitives
				(gr_poly
					(pts
						(arc
							(start 0.3048 -0.2032)
							(mid 0.275042 -0.275042)
							(end 0.2032 -0.3048)
						)
						(arc
							(start -0.2032 -0.3048)
							(mid -0.275042 -0.275042)
							(end -0.3048 -0.2032)
						)
						(arc
							(start -0.3048 0.2032)
							(mid -0.275042 0.275042)
							(end -0.2032 0.3048)
						)
						(arc
							(start 0.2032 0.3048)
							(mid 0.275042 0.275042)
							(end 0.3048 0.2032)
						)
					)
					(width 0)
					(fill yes)
				)
			)
		)
	)
	(footprint ""
		(layer "F.Cu")
		(at 8.2042 -135.509 90)
		(property "Reference" "R687"
			(at 0 0 90)
			(layer "F.SilkS")
			(hide yes)
			(effects
				(font
					(size 1.27 1.27)
				)
			)
		)
		(property "Value" "0R2J-2-GP"
			(at 0.064008 -3.993896 90)
			(unlocked yes)
			(layer "F.Fab")
			(hide yes)
			(effects
				(font
					(size 1.016 1.016)
					(thickness 0.1524)
				)
			)
		)
		(property "Device Type" "R402H16"
			(at 0.064008 -5.517896 90)
			(unlocked yes)
			(layer "F.Fab")
			(hide yes)
			(effects
				(font
					(size 1.016 1.016)
					(thickness 0.1524)
				)
			)
		)
		(duplicate_pad_numbers_are_jumpers no)
		(fp_line
			(start 0.508 -0.9398)
			(end -0.508 -0.9398)
			(stroke
				(width 0.1524)
				(type default)
			)
			(layer "F.SilkS")
		)
		(fp_line
			(start -0.508 -0.9398)
			(end -0.508 0.9398)
			(stroke
				(width 0.1524)
				(type default)
			)
			(layer "F.SilkS")
		)
		(fp_rect
			(start -0.508 0.9398)
			(end 0.508 -0.9398)
			(stroke
				(width 0)
				(type default)
			)
			(fill no)
			(layer "F.CrtYd")
		)
		(fp_rect
			(start -0.508 0.9398)
			(end 0.508 -0.9398)
			(stroke
				(width 0)
				(type default)
			)
			(fill no)
			(layer "F.Fab")
		)
		(pad "1" smd custom
			(at 0 -0.4445 90)
			(size 0.1397 0.1397)
			(layers "F.Cu" "F.Mask" "F.Paste")
			(net "FM_BMC_RESET_Q36")
			(options
				(clearance outline)
				(anchor circle)
			)
			(primitives
				(gr_poly
					(pts
						(arc
							(start -0.1778 -0.2794)
							(mid -0.249642 -0.249642)
							(end -0.2794 -0.1778)
						)
						(arc
							(start -0.2794 0.1778)
							(mid -0.249642 0.249642)
							(end -0.1778 0.2794)
						)
						(arc
							(start 0.1778 0.2794)
							(mid 0.249642 0.249642)
							(end 0.2794 0.1778)
						)
						(arc
							(start 0.2794 -0.1778)
							(mid 0.249642 -0.249642)
							(end 0.1778 -0.2794)
						)
					)
					(width 0)
					(fill yes)
				)
			)
		)
		(pad "2" smd custom
			(at 0 0.4445 90)
			(size 0.1397 0.1397)
			(layers "F.Cu" "F.Mask" "F.Paste")
			(net "TRAY_RESET_N_R")
			(options
				(clearance outline)
				(anchor circle)
			)
			(primitives
				(gr_poly
					(pts
						(arc
							(start -0.1778 -0.2794)
							(mid -0.249642 -0.249642)
							(end -0.2794 -0.1778)
						)
						(arc
							(start -0.2794 0.1778)
							(mid -0.249642 0.249642)
							(end -0.1778 0.2794)
						)
						(arc
							(start 0.1778 0.2794)
							(mid 0.249642 0.249642)
							(end 0.2794 0.1778)
						)
						(arc
							(start 0.2794 -0.1778)
							(mid 0.249642 -0.249642)
							(end 0.1778 -0.2794)
						)
					)
					(width 0)
					(fill yes)
				)
			)
		)
	)
	(footprint ""
		(layer "F.Cu")
		(at 25.4508 -98.1964)
		(property "Reference" "R495"
			(at 0 0 0)
			(layer "F.SilkS")
			(hide yes)
			(effects
				(font
					(size 1.27 1.27)
				)
			)
		)
		(property "Value" "0R2J-2-GP"
			(at 0.064008 -3.993896 0)
			(unlocked yes)
			(layer "F.Fab")
			(hide yes)
			(effects
				(font
					(size 1.016 1.016)
					(thickness 0.1524)
				)
			)
		)
		(property "Device Type" "R402H16"
			(at 0.064008 -5.517896 0)
			(unlocked yes)
			(layer "F.Fab")
			(hide yes)
			(effects
				(font
					(size 1.016 1.016)
					(thickness 0.1524)
				)
			)
		)
		(duplicate_pad_numbers_are_jumpers no)
		(fp_line
			(start -0.508 -0.9398)
			(end -0.508 0.9398)
			(stroke
				(width 0.1524)
				(type default)
			)
			(layer "F.SilkS")
		)
		(fp_line
			(start 0.508 -0.9398)
			(end -0.508 -0.9398)
			(stroke
				(width 0.1524)
				(type default)
			)
			(layer "F.SilkS")
		)
		(fp_rect
			(start -0.508 0.9398)
			(end 0.508 -0.9398)
			(stroke
				(width 0)
				(type default)
			)
			(fill no)
			(layer "F.CrtYd")
		)
		(fp_rect
			(start -0.508 0.9398)
			(end 0.508 -0.9398)
			(stroke
				(width 0)
				(type default)
			)
			(fill no)
			(layer "F.Fab")
		)
		(pad "1" smd custom
			(at 0 -0.4445)
			(size 0.1397 0.1397)
			(layers "F.Cu" "F.Mask" "F.Paste")
			(net "FM_TPM_PRES_RST_N_C")
			(options
				(clearance outline)
				(anchor circle)
			)
			(primitives
				(gr_poly
					(pts
						(arc
							(start -0.1778 -0.2794)
							(mid -0.249642 -0.249642)
							(end -0.2794 -0.1778)
						)
						(arc
							(start -0.2794 0.1778)
							(mid -0.249642 0.249642)
							(end -0.1778 0.2794)
						)
						(arc
							(start 0.1778 0.2794)
							(mid 0.249642 0.249642)
							(end 0.2794 0.1778)
						)
						(arc
							(start 0.2794 -0.1778)
							(mid 0.249642 -0.249642)
							(end 0.1778 -0.2794)
						)
					)
					(width 0)
					(fill yes)
				)
			)
		)
		(pad "2" smd custom
			(at 0 0.4445)
			(size 0.1397 0.1397)
			(layers "F.Cu" "F.Mask" "F.Paste")
			(net "FM_TPM_PRES_RST_N")
			(options
				(clearance outline)
				(anchor circle)
			)
			(primitives
				(gr_poly
					(pts
						(arc
							(start -0.1778 -0.2794)
							(mid -0.249642 -0.249642)
							(end -0.2794 -0.1778)
						)
						(arc
							(start -0.2794 0.1778)
							(mid -0.249642 0.249642)
							(end -0.1778 0.2794)
						)
						(arc
							(start 0.1778 0.2794)
							(mid 0.249642 0.249642)
							(end 0.2794 0.1778)
						)
						(arc
							(start 0.2794 -0.1778)
							(mid 0.249642 -0.249642)
							(end 0.1778 -0.2794)
						)
					)
					(width 0)
					(fill yes)
				)
			)
		)
	)
	(footprint ""
		(layer "F.Cu")
		(at 203.192126 -212.420454 180)
		(property "Reference" "C115"
			(at 0 0 180)
			(layer "F.SilkS")
			(hide yes)
			(effects
				(font
					(size 1.27 1.27)
				)
			)
		)
		(property "Value" "SCD22U10V2KX-1GP"
			(at 1.1811 -2.7051 180)
			(unlocked yes)
			(layer "F.Fab")
			(hide yes)
			(effects
				(font
					(size 1.016 1.016)
					(thickness 0.1524)
				)
			)
		)
		(property "Device Type" "C402H22"
			(at 1.1811 -4.2291 180)
			(unlocked yes)
			(layer "F.Fab")
			(hide yes)
			(effects
				(font
					(size 1.016 1.016)
					(thickness 0.1524)
				)
			)
		)
		(duplicate_pad_numbers_are_jumpers no)
		(fp_rect
			(start -0.4318 0.9525)
			(end 0.4318 -0.9525)
			(stroke
				(width 0)
				(type default)
			)
			(fill no)
			(layer "F.CrtYd")
		)
		(fp_rect
			(start -0.4318 0.9525)
			(end 0.4318 -0.9525)
			(stroke
				(width 0)
				(type default)
			)
			(fill no)
			(layer "F.Fab")
		)
		(pad "1" smd custom
			(at 0 -0.4445 180)
			(size 0.1524 0.1524)
			(layers "F.Cu" "F.Mask" "F.Paste")
			(net "PCIE_TX_CAP_P41")
			(options
				(clearance outline)
				(anchor circle)
			)
			(primitives
				(gr_poly
					(pts
						(arc
							(start 0.3048 -0.2032)
							(mid 0.275042 -0.275042)
							(end 0.2032 -0.3048)
						)
						(arc
							(start -0.2032 -0.3048)
							(mid -0.275042 -0.275042)
							(end -0.3048 -0.2032)
						)
						(arc
							(start -0.3048 0.2032)
							(mid -0.275042 0.275042)
							(end -0.2032 0.3048)
						)
						(arc
							(start 0.2032 0.3048)
							(mid 0.275042 0.275042)
							(end 0.3048 0.2032)
						)
					)
					(width 0)
					(fill yes)
				)
			)
		)
		(pad "2" smd custom
			(at 0 0.4445 180)
			(size 0.1524 0.1524)
			(layers "F.Cu" "F.Mask" "F.Paste")
			(net "PCIE_TX_P41")
			(options
				(clearance outline)
				(anchor circle)
			)
			(primitives
				(gr_poly
					(pts
						(arc
							(start 0.3048 -0.2032)
							(mid 0.275042 -0.275042)
							(end 0.2032 -0.3048)
						)
						(arc
							(start -0.2032 -0.3048)
							(mid -0.275042 -0.275042)
							(end -0.3048 -0.2032)
						)
						(arc
							(start -0.3048 0.2032)
							(mid -0.275042 0.275042)
							(end -0.2032 0.3048)
						)
						(arc
							(start 0.2032 0.3048)
							(mid 0.275042 0.275042)
							(end 0.3048 0.2032)
						)
					)
					(width 0)
					(fill yes)
				)
			)
		)
	)
	(footprint ""
		(layer "F.Cu")
		(at 166.116 -87.5284 90)
		(property "Reference" "R87"
			(at 0 0 90)
			(layer "F.SilkS")
			(hide yes)
			(effects
				(font
					(size 1.27 1.27)
				)
			)
		)
		(property "Value" "0R2J-2-GP"
			(at 0.064008 -3.993896 90)
			(unlocked yes)
			(layer "F.Fab")
			(hide yes)
			(effects
				(font
					(size 1.016 1.016)
					(thickness 0.1524)
				)
			)
		)
		(property "Device Type" "R402H16"
			(at 0.064008 -5.517896 90)
			(unlocked yes)
			(layer "F.Fab")
			(hide yes)
			(effects
				(font
					(size 1.016 1.016)
					(thickness 0.1524)
				)
			)
		)
		(duplicate_pad_numbers_are_jumpers no)
		(fp_line
			(start 0.508 -0.9398)
			(end -0.508 -0.9398)
			(stroke
				(width 0.1524)
				(type default)
			)
			(layer "F.SilkS")
		)
		(fp_line
			(start -0.508 -0.9398)
			(end -0.508 0.9398)
			(stroke
				(width 0.1524)
				(type default)
			)
			(layer "F.SilkS")
		)
		(fp_rect
			(start -0.508 0.9398)
			(end 0.508 -0.9398)
			(stroke
				(width 0)
				(type default)
			)
			(fill no)
			(layer "F.CrtYd")
		)
		(fp_rect
			(start -0.508 0.9398)
			(end 0.508 -0.9398)
			(stroke
				(width 0)
				(type default)
			)
			(fill no)
			(layer "F.Fab")
		)
		(pad "1" smd custom
			(at 0 -0.4445 90)
			(size 0.1397 0.1397)
			(layers "F.Cu" "F.Mask" "F.Paste")
			(net "CLKGEN_OE1_R")
			(options
				(clearance outline)
				(anchor circle)
			)
			(primitives
				(gr_poly
					(pts
						(arc
							(start -0.1778 -0.2794)
							(mid -0.249642 -0.249642)
							(end -0.2794 -0.1778)
						)
						(arc
							(start -0.2794 0.1778)
							(mid -0.249642 0.249642)
							(end -0.1778 0.2794)
						)
						(arc
							(start 0.1778 0.2794)
							(mid 0.249642 0.249642)
							(end 0.2794 0.1778)
						)
						(arc
							(start 0.2794 -0.1778)
							(mid 0.249642 -0.249642)
							(end 0.1778 -0.2794)
						)
					)
					(width 0)
					(fill yes)
				)
			)
		)
		(pad "2" smd custom
			(at 0 0.4445 90)
			(size 0.1397 0.1397)
			(layers "F.Cu" "F.Mask" "F.Paste")
			(net "CLKGEN_OE1")
			(options
				(clearance outline)
				(anchor circle)
			)
			(primitives
				(gr_poly
					(pts
						(arc
							(start -0.1778 -0.2794)
							(mid -0.249642 -0.249642)
							(end -0.2794 -0.1778)
						)
						(arc
							(start -0.2794 0.1778)
							(mid -0.249642 0.249642)
							(end -0.1778 0.2794)
						)
						(arc
							(start 0.1778 0.2794)
							(mid 0.249642 0.249642)
							(end 0.2794 0.1778)
						)
						(arc
							(start 0.2794 -0.1778)
							(mid 0.249642 -0.249642)
							(end 0.1778 -0.2794)
						)
					)
					(width 0)
					(fill yes)
				)
			)
		)
	)
)
